(kicad_pcb
	(version 20260206)
	(generator "pcbnew")
	(generator_version "10.0")
	(general
		(thickness 1.6)
		(legacy_teardrops no)
	)
	(paper "A4")
	(title_block
		(title "03242023_DA0F0TMBIJ0_F0T_Motherboard_J_brd_V01_OCP.brd")
		(comment 1 "Grand Teton / footprints 2106-2112 of 6105")
	)
	(layers
		(0 "F.Cu" signal "TOP")
		(4 "In1.Cu" signal "GND")
		(6 "In2.Cu" signal "IN1")
		(8 "In3.Cu" signal "GND1")
		(10 "In4.Cu" signal "IN2")
		(12 "In5.Cu" signal "GND2")
		(14 "In6.Cu" signal "IN3")
		(16 "In7.Cu" signal "GND3")
		(18 "In8.Cu" signal "VCC")
		(20 "In9.Cu" signal "VCC1")
		(22 "In10.Cu" signal "GND4")
		(24 "In11.Cu" signal "IN4")
		(26 "In12.Cu" signal "GND5")
		(28 "In13.Cu" signal "IN5")
		(30 "In14.Cu" signal "GND6")
		(32 "In15.Cu" signal "IN6")
		(34 "In16.Cu" signal "GND7")
		(2 "B.Cu" signal "BOTTOM")
		(9 "F.Adhes" user "F.Adhesive")
		(11 "B.Adhes" user "B.Adhesive")
		(13 "F.Paste" user "Package Geometry/Pastemask Top")
		(15 "B.Paste" user "Package Geometry/Pastemask Bottom")
		(5 "F.SilkS" user "Ref Des/Silkscreen Top")
		(7 "B.SilkS" user "Ref Des/Silkscreen Bottom")
		(1 "F.Mask" user "Board Geometry/Soldermask Top")
		(3 "B.Mask" user "Board Geometry/Soldermask Bottom")
		(17 "Dwgs.User" user "User.Drawings")
		(19 "Cmts.User" user "User.Comments")
		(21 "Eco1.User" user "User.Eco1")
		(23 "Eco2.User" user "User.Eco2")
		(25 "Edge.Cuts" user "Board Geometry/Outline")
		(27 "Margin" user)
		(31 "F.CrtYd" user "Package Geometry/Place Bound Top")
		(29 "B.CrtYd" user "Package Geometry/Place Bound Bottom")
		(35 "F.Fab" user "Ref Des/Assembly Top")
		(33 "B.Fab" user "Ref Des/Assembly Bottom")
	)
	(footprint ""
		(layer "F.Cu")
		(at 315.946028 -25.09139)
		(property "Reference" "R1442"
			(at 0 0 0)
			(layer "F.SilkS")
			(hide yes)
			(effects
				(font
					(size 1.27 1.27)
				)
			)
		)
		(property "Value" ""
			(at 0 0 0)
			(layer "F.Fab")
			(effects
				(font
					(size 1.27 1.27)
				)
			)
		)
		(duplicate_pad_numbers_are_jumpers no)
		(fp_line
			(start -0.7874 -0.4064)
			(end 0.7874 -0.4064)
			(stroke
				(width 0.1524)
				(type default)
			)
			(layer "F.SilkS")
		)
		(fp_line
			(start -0.7874 0.4064)
			(end -0.7874 -0.4064)
			(stroke
				(width 0.1524)
				(type default)
			)
			(layer "F.SilkS")
		)
		(fp_line
			(start 0.7874 -0.4064)
			(end 0.7874 0.4064)
			(stroke
				(width 0.1524)
				(type default)
			)
			(layer "F.SilkS")
		)
		(fp_line
			(start 0.7874 0.4064)
			(end -0.7874 0.4064)
			(stroke
				(width 0.1524)
				(type default)
			)
			(layer "F.SilkS")
		)
		(fp_line
			(start -0.67945 -0.305054)
			(end -0.12065 -0.305054)
			(stroke
				(width 0.1)
				(type default)
			)
			(layer "F.Fab")
		)
		(fp_line
			(start -0.67945 0.3048)
			(end -0.67945 -0.305054)
			(stroke
				(width 0.1)
				(type default)
			)
			(layer "F.Fab")
		)
		(fp_line
			(start -0.12065 -0.305054)
			(end -0.12065 -0.2794)
			(stroke
				(width 0.1)
				(type default)
			)
			(layer "F.Fab")
		)
		(fp_line
			(start -0.12065 -0.2794)
			(end 0.12065 -0.2794)
			(stroke
				(width 0.1)
				(type default)
			)
			(layer "F.Fab")
		)
		(fp_line
			(start -0.12065 0.2794)
			(end -0.12065 0.3048)
			(stroke
				(width 0.1)
				(type default)
			)
			(layer "F.Fab")
		)
		(fp_line
			(start -0.12065 0.3048)
			(end -0.67945 0.3048)
			(stroke
				(width 0.1)
				(type default)
			)
			(layer "F.Fab")
		)
		(fp_line
			(start 0.120396 0.2794)
			(end -0.12065 0.2794)
			(stroke
				(width 0.1)
				(type default)
			)
			(layer "F.Fab")
		)
		(fp_line
			(start 0.120396 0.3048)
			(end 0.120396 0.2794)
			(stroke
				(width 0.1)
				(type default)
			)
			(layer "F.Fab")
		)
		(fp_line
			(start 0.12065 -0.3048)
			(end 0.67945 -0.3048)
			(stroke
				(width 0.1)
				(type default)
			)
			(layer "F.Fab")
		)
		(fp_line
			(start 0.12065 -0.2794)
			(end 0.12065 -0.3048)
			(stroke
				(width 0.1)
				(type default)
			)
			(layer "F.Fab")
		)
		(fp_line
			(start 0.67945 -0.3048)
			(end 0.67945 0.3048)
			(stroke
				(width 0.1)
				(type default)
			)
			(layer "F.Fab")
		)
		(fp_line
			(start 0.67945 0.3048)
			(end 0.120396 0.3048)
			(stroke
				(width 0.1)
				(type default)
			)
			(layer "F.Fab")
		)
		(pad "1" smd circle
			(at -0.40005 0)
			(size 0 0)
			(layers "F.Cu" "F.Mask" "F.Paste")
			(net "PWRGD_PCH_PWROK_R")
		)
		(pad "2" smd circle
			(at 0.40005 0)
			(size 0 0)
			(layers "F.Cu" "F.Mask" "F.Paste")
			(net "PWRGD_PCH_PWROK")
		)
	)
	(footprint ""
		(layer "F.Cu")
		(at 204.93736 -114.264948 180)
		(property "Reference" "R4147"
			(at 0 0 180)
			(layer "F.SilkS")
			(hide yes)
			(effects
				(font
					(size 1.27 1.27)
				)
			)
		)
		(property "Value" ""
			(at 0 0 180)
			(layer "F.Fab")
			(effects
				(font
					(size 1.27 1.27)
				)
			)
		)
		(duplicate_pad_numbers_are_jumpers no)
		(fp_line
			(start 0.7874 0.4064)
			(end -0.7874 0.4064)
			(stroke
				(width 0.1524)
				(type default)
			)
			(layer "F.SilkS")
		)
		(fp_line
			(start 0.7874 -0.4064)
			(end 0.7874 0.4064)
			(stroke
				(width 0.1524)
				(type default)
			)
			(layer "F.SilkS")
		)
		(fp_line
			(start -0.7874 0.4064)
			(end -0.7874 -0.4064)
			(stroke
				(width 0.1524)
				(type default)
			)
			(layer "F.SilkS")
		)
		(fp_line
			(start -0.7874 -0.4064)
			(end 0.7874 -0.4064)
			(stroke
				(width 0.1524)
				(type default)
			)
			(layer "F.SilkS")
		)
		(fp_line
			(start 0.67945 0.3048)
			(end 0.120396 0.3048)
			(stroke
				(width 0.1)
				(type default)
			)
			(layer "F.Fab")
		)
		(fp_line
			(start 0.67945 -0.3048)
			(end 0.67945 0.3048)
			(stroke
				(width 0.1)
				(type default)
			)
			(layer "F.Fab")
		)
		(fp_line
			(start 0.12065 -0.2794)
			(end 0.12065 -0.3048)
			(stroke
				(width 0.1)
				(type default)
			)
			(layer "F.Fab")
		)
		(fp_line
			(start 0.12065 -0.3048)
			(end 0.67945 -0.3048)
			(stroke
				(width 0.1)
				(type default)
			)
			(layer "F.Fab")
		)
		(fp_line
			(start 0.120396 0.3048)
			(end 0.120396 0.2794)
			(stroke
				(width 0.1)
				(type default)
			)
			(layer "F.Fab")
		)
		(fp_line
			(start 0.120396 0.2794)
			(end -0.12065 0.2794)
			(stroke
				(width 0.1)
				(type default)
			)
			(layer "F.Fab")
		)
		(fp_line
			(start -0.12065 0.3048)
			(end -0.67945 0.3048)
			(stroke
				(width 0.1)
				(type default)
			)
			(layer "F.Fab")
		)
		(fp_line
			(start -0.12065 0.2794)
			(end -0.12065 0.3048)
			(stroke
				(width 0.1)
				(type default)
			)
			(layer "F.Fab")
		)
		(fp_line
			(start -0.12065 -0.2794)
			(end 0.12065 -0.2794)
			(stroke
				(width 0.1)
				(type default)
			)
			(layer "F.Fab")
		)
		(fp_line
			(start -0.12065 -0.305054)
			(end -0.12065 -0.2794)
			(stroke
				(width 0.1)
				(type default)
			)
			(layer "F.Fab")
		)
		(fp_line
			(start -0.67945 0.3048)
			(end -0.67945 -0.305054)
			(stroke
				(width 0.1)
				(type default)
			)
			(layer "F.Fab")
		)
		(fp_line
			(start -0.67945 -0.305054)
			(end -0.12065 -0.305054)
			(stroke
				(width 0.1)
				(type default)
			)
			(layer "F.Fab")
		)
		(pad "1" smd circle
			(at -0.40005 0 180)
			(size 0 0)
			(layers "F.Cu" "F.Mask" "F.Paste")
			(net "PRSNT_CABLE_GPU_A2_ISO_N")
		)
		(pad "2" smd circle
			(at 0.40005 0 180)
			(size 0 0)
			(layers "F.Cu" "F.Mask" "F.Paste")
			(net "PRSNT_CABLE_GPU_A2_ISO_R_N")
		)
	)
	(footprint ""
		(layer "F.Cu")
		(at 437.875172 -28.668218)
		(property "Reference" "R4532"
			(at 0 0 0)
			(layer "F.SilkS")
			(hide yes)
			(effects
				(font
					(size 1.27 1.27)
				)
			)
		)
		(property "Value" ""
			(at 0 0 0)
			(layer "F.Fab")
			(effects
				(font
					(size 1.27 1.27)
				)
			)
		)
		(duplicate_pad_numbers_are_jumpers no)
		(fp_line
			(start -0.7874 -0.4064)
			(end 0.7874 -0.4064)
			(stroke
				(width 0.1524)
				(type default)
			)
			(layer "F.SilkS")
		)
		(fp_line
			(start -0.7874 0.4064)
			(end -0.7874 -0.4064)
			(stroke
				(width 0.1524)
				(type default)
			)
			(layer "F.SilkS")
		)
		(fp_line
			(start 0.7874 -0.4064)
			(end 0.7874 0.4064)
			(stroke
				(width 0.1524)
				(type default)
			)
			(layer "F.SilkS")
		)
		(fp_line
			(start 0.7874 0.4064)
			(end -0.7874 0.4064)
			(stroke
				(width 0.1524)
				(type default)
			)
			(layer "F.SilkS")
		)
		(fp_line
			(start -0.67945 -0.305054)
			(end -0.12065 -0.305054)
			(stroke
				(width 0.1)
				(type default)
			)
			(layer "F.Fab")
		)
		(fp_line
			(start -0.67945 0.3048)
			(end -0.67945 -0.305054)
			(stroke
				(width 0.1)
				(type default)
			)
			(layer "F.Fab")
		)
		(fp_line
			(start -0.12065 -0.305054)
			(end -0.12065 -0.2794)
			(stroke
				(width 0.1)
				(type default)
			)
			(layer "F.Fab")
		)
		(fp_line
			(start -0.12065 -0.2794)
			(end 0.12065 -0.2794)
			(stroke
				(width 0.1)
				(type default)
			)
			(layer "F.Fab")
		)
		(fp_line
			(start -0.12065 0.2794)
			(end -0.12065 0.3048)
			(stroke
				(width 0.1)
				(type default)
			)
			(layer "F.Fab")
		)
		(fp_line
			(start -0.12065 0.3048)
			(end -0.67945 0.3048)
			(stroke
				(width 0.1)
				(type default)
			)
			(layer "F.Fab")
		)
		(fp_line
			(start 0.120396 0.2794)
			(end -0.12065 0.2794)
			(stroke
				(width 0.1)
				(type default)
			)
			(layer "F.Fab")
		)
		(fp_line
			(start 0.120396 0.3048)
			(end 0.120396 0.2794)
			(stroke
				(width 0.1)
				(type default)
			)
			(layer "F.Fab")
		)
		(fp_line
			(start 0.12065 -0.3048)
			(end 0.67945 -0.3048)
			(stroke
				(width 0.1)
				(type default)
			)
			(layer "F.Fab")
		)
		(fp_line
			(start 0.12065 -0.2794)
			(end 0.12065 -0.3048)
			(stroke
				(width 0.1)
				(type default)
			)
			(layer "F.Fab")
		)
		(fp_line
			(start 0.67945 -0.3048)
			(end 0.67945 0.3048)
			(stroke
				(width 0.1)
				(type default)
			)
			(layer "F.Fab")
		)
		(fp_line
			(start 0.67945 0.3048)
			(end 0.120396 0.3048)
			(stroke
				(width 0.1)
				(type default)
			)
			(layer "F.Fab")
		)
		(pad "1" smd circle
			(at -0.40005 0)
			(size 0 0)
			(layers "F.Cu" "F.Mask" "F.Paste")
			(net "P3V3_AUX")
		)
		(pad "2" smd circle
			(at 0.40005 0)
			(size 0 0)
			(layers "F.Cu" "F.Mask" "F.Paste")
			(net "HP_LVC3_OCP_V3_1_P12V_PWRGD")
		)
	)
	(footprint ""
		(layer "F.Cu")
		(at 8.80872 -76.827888)
		(property "Reference" "C1875"
			(at 0 0 0)
			(layer "F.SilkS")
			(hide yes)
			(effects
				(font
					(size 1.27 1.27)
				)
			)
		)
		(property "Value" ""
			(at 0 0 0)
			(layer "F.Fab")
			(effects
				(font
					(size 1.27 1.27)
				)
			)
		)
		(duplicate_pad_numbers_are_jumpers no)
		(fp_line
			(start -0.7874 -0.4064)
			(end 0.7874 -0.4064)
			(stroke
				(width 0.1524)
				(type default)
			)
			(layer "F.SilkS")
		)
		(fp_line
			(start -0.7874 0.4064)
			(end -0.7874 -0.4064)
			(stroke
				(width 0.1524)
				(type default)
			)
			(layer "F.SilkS")
		)
		(fp_line
			(start 0.7874 -0.4064)
			(end 0.7874 0.4064)
			(stroke
				(width 0.1524)
				(type default)
			)
			(layer "F.SilkS")
		)
		(fp_line
			(start 0.7874 0.4064)
			(end -0.7874 0.4064)
			(stroke
				(width 0.1524)
				(type default)
			)
			(layer "F.SilkS")
		)
		(fp_line
			(start -0.67945 -0.305054)
			(end -0.12065 -0.305054)
			(stroke
				(width 0.1)
				(type default)
			)
			(layer "F.Fab")
		)
		(fp_line
			(start -0.67945 0.3048)
			(end -0.67945 -0.305054)
			(stroke
				(width 0.1)
				(type default)
			)
			(layer "F.Fab")
		)
		(fp_line
			(start -0.12065 -0.305054)
			(end -0.12065 -0.2794)
			(stroke
				(width 0.1)
				(type default)
			)
			(layer "F.Fab")
		)
		(fp_line
			(start -0.12065 -0.2794)
			(end 0.12065 -0.2794)
			(stroke
				(width 0.1)
				(type default)
			)
			(layer "F.Fab")
		)
		(fp_line
			(start -0.12065 0.2794)
			(end -0.12065 0.3048)
			(stroke
				(width 0.1)
				(type default)
			)
			(layer "F.Fab")
		)
		(fp_line
			(start -0.12065 0.3048)
			(end -0.67945 0.3048)
			(stroke
				(width 0.1)
				(type default)
			)
			(layer "F.Fab")
		)
		(fp_line
			(start 0.120396 0.2794)
			(end -0.12065 0.2794)
			(stroke
				(width 0.1)
				(type default)
			)
			(layer "F.Fab")
		)
		(fp_line
			(start 0.120396 0.3048)
			(end 0.120396 0.2794)
			(stroke
				(width 0.1)
				(type default)
			)
			(layer "F.Fab")
		)
		(fp_line
			(start 0.12065 -0.3048)
			(end 0.67945 -0.3048)
			(stroke
				(width 0.1)
				(type default)
			)
			(layer "F.Fab")
		)
		(fp_line
			(start 0.12065 -0.2794)
			(end 0.12065 -0.3048)
			(stroke
				(width 0.1)
				(type default)
			)
			(layer "F.Fab")
		)
		(fp_line
			(start 0.67945 -0.3048)
			(end 0.67945 0.3048)
			(stroke
				(width 0.1)
				(type default)
			)
			(layer "F.Fab")
		)
		(fp_line
			(start 0.67945 0.3048)
			(end 0.120396 0.3048)
			(stroke
				(width 0.1)
				(type default)
			)
			(layer "F.Fab")
		)
		(pad "1" smd circle
			(at -0.40005 0)
			(size 0 0)
			(layers "F.Cu" "F.Mask" "F.Paste")
			(net "P3V3_AUX")
		)
		(pad "2" smd circle
			(at 0.40005 0)
			(size 0 0)
			(layers "F.Cu" "F.Mask" "F.Paste")
			(net "GND")
		)
	)
	(footprint ""
		(layer "F.Cu")
		(at 125.711204 -366.689132 90)
		(property "Reference" "PL119"
			(at -3.896614 4.481576 0)
			(unlocked yes)
			(layer "F.SilkS")
			(effects
				(font
					(size 0.7874 0.5842)
					(thickness 0.1524)
				)
				(justify left)
			)
		)
		(property "Value" ""
			(at 0 0 90)
			(layer "F.Fab")
			(effects
				(font
					(size 1.27 1.27)
				)
			)
		)
		(duplicate_pad_numbers_are_jumpers no)
		(fp_line
			(start 3.64998 -3.350006)
			(end 3.64998 -1.8034)
			(stroke
				(width 0.1524)
				(type default)
			)
			(layer "F.SilkS")
		)
		(fp_line
			(start -3.6576 -3.350006)
			(end 3.64998 -3.350006)
			(stroke
				(width 0.1524)
				(type default)
			)
			(layer "F.SilkS")
		)
		(fp_line
			(start -3.64998 -1.8034)
			(end -3.64998 -3.350006)
			(stroke
				(width 0.1524)
				(type default)
			)
			(layer "F.SilkS")
		)
		(fp_line
			(start 3.64998 1.8034)
			(end 3.64998 3.350006)
			(stroke
				(width 0.1524)
				(type default)
			)
			(layer "F.SilkS")
		)
		(fp_line
			(start 3.64998 3.350006)
			(end -3.64998 3.350006)
			(stroke
				(width 0.1524)
				(type default)
			)
			(layer "F.SilkS")
		)
		(fp_line
			(start -3.64998 3.350006)
			(end -3.64998 1.8288)
			(stroke
				(width 0.1524)
				(type default)
			)
			(layer "F.SilkS")
		)
		(fp_line
			(start 3.64998 -3.350006)
			(end 3.64998 3.350006)
			(stroke
				(width 0.1)
				(type default)
			)
			(layer "F.Fab")
		)
		(fp_line
			(start -3.64998 -3.350006)
			(end 3.64998 -3.350006)
			(stroke
				(width 0.1)
				(type default)
			)
			(layer "F.Fab")
		)
		(fp_line
			(start 3.64998 3.350006)
			(end -3.64998 3.350006)
			(stroke
				(width 0.1)
				(type default)
			)
			(layer "F.Fab")
		)
		(fp_line
			(start -3.64998 3.350006)
			(end -3.64998 -3.350006)
			(stroke
				(width 0.1)
				(type default)
			)
			(layer "F.Fab")
		)
		(pad "1" smd rect
			(at -2.92481 0 90)
			(size 2.15392 3.302)
			(layers "F.Cu" "F.Mask" "F.Paste")
			(net "SW_PVPP_HBM_CPU1_SW")
		)
		(pad "2" smd rect
			(at 2.92481 0 90)
			(size 2.15392 3.302)
			(layers "F.Cu" "F.Mask" "F.Paste")
			(net "PVPP_HBM_CPU1")
		)
	)
	(footprint ""
		(layer "F.Cu")
		(at 371.39753 -402.371052 -90)
		(property "Reference" "C934"
			(at 0 0 270)
			(layer "F.SilkS")
			(hide yes)
			(effects
				(font
					(size 1.27 1.27)
				)
			)
		)
		(property "Value" ""
			(at 0 0 270)
			(layer "F.Fab")
			(effects
				(font
					(size 1.27 1.27)
				)
			)
		)
		(duplicate_pad_numbers_are_jumpers no)
		(fp_line
			(start -0.299974 0.150114)
			(end -0.299974 -0.150114)
			(stroke
				(width 0.1)
				(type default)
			)
			(layer "F.Fab")
		)
		(fp_line
			(start 0.299974 0.150114)
			(end -0.299974 0.150114)
			(stroke
				(width 0.1)
				(type default)
			)
			(layer "F.Fab")
		)
		(fp_line
			(start -0.299974 -0.150114)
			(end 0.299974 -0.150114)
			(stroke
				(width 0.1)
				(type default)
			)
			(layer "F.Fab")
		)
		(fp_line
			(start 0.299974 -0.150114)
			(end 0.299974 0.150114)
			(stroke
				(width 0.1)
				(type default)
			)
			(layer "F.Fab")
		)
		(pad "1" smd rect
			(at -0.2667 0 270)
			(size 0.3048 0.381)
			(layers "F.Cu" "F.Mask" "F.Paste")
			(net "P5E_CPU0_PE2_TX_C_DN<15>")
		)
		(pad "2" smd rect
			(at 0.2667 0 270)
			(size 0.3048 0.381)
			(layers "F.Cu" "F.Mask" "F.Paste")
			(net "P5E_CPU0_PE2_TX_DN<15>")
		)
	)
	(footprint ""
		(layer "F.Cu")
		(at 451.81774 -113.172748 -90)
		(property "Reference" "C578"
			(at 0 0 270)
			(layer "F.SilkS")
			(hide yes)
			(effects
				(font
					(size 1.27 1.27)
				)
			)
		)
		(property "Value" ""
			(at 0 0 270)
			(layer "F.Fab")
			(effects
				(font
					(size 1.27 1.27)
				)
			)
		)
		(duplicate_pad_numbers_are_jumpers no)
		(fp_line
			(start -0.7874 0.4064)
			(end -0.7874 -0.4064)
			(stroke
				(width 0.1524)
				(type default)
			)
			(layer "F.SilkS")
		)
		(fp_line
			(start 0.7874 0.4064)
			(end -0.7874 0.4064)
			(stroke
				(width 0.1524)
				(type default)
			)
			(layer "F.SilkS")
		)
		(fp_line
			(start -0.7874 -0.4064)
			(end 0.7874 -0.4064)
			(stroke
				(width 0.1524)
				(type default)
			)
			(layer "F.SilkS")
		)
		(fp_line
			(start 0.7874 -0.4064)
			(end 0.7874 0.4064)
			(stroke
				(width 0.1524)
				(type default)
			)
			(layer "F.SilkS")
		)
		(fp_line
			(start -0.67945 0.3048)
			(end -0.67945 -0.305054)
			(stroke
				(width 0.1)
				(type default)
			)
			(layer "F.Fab")
		)
		(fp_line
			(start -0.12065 0.3048)
			(end -0.67945 0.3048)
			(stroke
				(width 0.1)
				(type default)
			)
			(layer "F.Fab")
		)
		(fp_line
			(start 0.120396 0.3048)
			(end 0.120396 0.2794)
			(stroke
				(width 0.1)
				(type default)
			)
			(layer "F.Fab")
		)
		(fp_line
			(start 0.67945 0.3048)
			(end 0.120396 0.3048)
			(stroke
				(width 0.1)
				(type default)
			)
			(layer "F.Fab")
		)
		(fp_line
			(start -0.12065 0.2794)
			(end -0.12065 0.3048)
			(stroke
				(width 0.1)
				(type default)
			)
			(layer "F.Fab")
		)
		(fp_line
			(start 0.120396 0.2794)
			(end -0.12065 0.2794)
			(stroke
				(width 0.1)
				(type default)
			)
			(layer "F.Fab")
		)
		(fp_line
			(start -0.12065 -0.2794)
			(end 0.12065 -0.2794)
			(stroke
				(width 0.1)
				(type default)
			)
			(layer "F.Fab")
		)
		(fp_line
			(start 0.12065 -0.2794)
			(end 0.12065 -0.3048)
			(stroke
				(width 0.1)
				(type default)
			)
			(layer "F.Fab")
		)
		(fp_line
			(start 0.12065 -0.3048)
			(end 0.67945 -0.3048)
			(stroke
				(width 0.1)
				(type default)
			)
			(layer "F.Fab")
		)
		(fp_line
			(start 0.67945 -0.3048)
			(end 0.67945 0.3048)
			(stroke
				(width 0.1)
				(type default)
			)
			(layer "F.Fab")
		)
		(fp_line
			(start -0.67945 -0.305054)
			(end -0.12065 -0.305054)
			(stroke
				(width 0.1)
				(type default)
			)
			(layer "F.Fab")
		)
		(fp_line
			(start -0.12065 -0.305054)
			(end -0.12065 -0.2794)
			(stroke
				(width 0.1)
				(type default)
			)
			(layer "F.Fab")
		)
		(pad "1" smd circle
			(at -0.40005 0 270)
			(size 0 0)
			(layers "F.Cu" "F.Mask" "F.Paste")
			(net "P3V3_AUX")
		)
		(pad "2" smd circle
			(at 0.40005 0 270)
			(size 0 0)
			(layers "F.Cu" "F.Mask" "F.Paste")
			(net "GND")
		)
	)
)
